# M2_ZED-F9T_MODULE.xlsx — M2_ZED-F9T_MODULE (bom)
| Comment | Description | Designator | Footprint | LibRef | Quantity | Digi-Key_Part_Number_1 | Digi-Key_Part_Number_2 | Digi-Key_Part_Number_3 | Manufacturer Part Number | Manufacturer Part Number 1 | Manufacturer_Part_Number |
| 1uF_25V_0402 | Cap Ceramic 1uF 25V X5R ±10% SMD 0402 +85°C Paper T/R | C1, C2, C3, C4, C5 | FP-CL542-IPC_C | CMP-13271-001051-1 | 5 |  |  |  |  |  |  |
| 47uF_6.3V_1206 | Chip Multilayer Ceramic Capacitors for General Purpose, 1206, 47uF, X5R, 15%, 20%, 6.3V | C6, C7 | FP-GRM31C-0_2-e0_3_0_8-IPC_C | CMP-2000-06344-2 | 2 |  |  |  |  |  |  |
| 100nF | None | C9, C10, C11 | FP-0402-L_1_0_0_05-W_0_5-IPC_B | CMP-14477-000330-2 | 3 |  |  |  |  |  |  |
| 10nF | Chip Multilayer Ceramic Capacitors for General Purpose, 0201, 10000pF, X7R, 15%, 10%, 16V | C12 | FP-GRM033-0_03-IPC_B | CMP-06035-000448-1 | 1 |  |  |  |  |  |  |
| PESD0402-140 | TVS DIODE 14V 40V 0402 | D1 | FP-PESD0402-MFG | CMP-08607-000011-1 | 1 |  |  |  | PESD0402-140 |  |  |
| LTST-C191KGKT | LED GREEN CLEAR SMD | D2, D3 | FP-LTST-C191KGKT-MFG | CMP-2000-05198-2 | 2 |  |  |  |  |  |  |
| 47nH 300mA | Multilayer type RF Inductor 47nH ±5% 0.72Ω 300mA 0402 | L1 | FP-LQG15HH_02-IPC_B | CMP-06042-015783-1 | 1 |  |  |  |  |  |  |
| U.FL-R-SMT-1(01) | Ultra Small Coaxial Connector, 6 GHz, -40 to 90 degC, 3-Pin SMD, RoHS, Bulk | P1 | HRS-U.FL-R-SMT-3_V | CMP-2000-05153-1 | 1 |  |  |  |  |  |  |
| NTR2101PT1G | Small Signal MOSFET, -8 V, -3.7 A, Single P-Channel, 3-Pin SOT-23, Pb-Free, Tape and Reel | Q1 | ONSC-SOT-23-3-318-08_V | CMP-1058-00758-1 | 1 |  |  |  |  |  |  |
| 1k | 1kΩ ±1% 0.063W 0402 Thick Film Chip Resistor AEC-Q200 compliant | R1, R4, R7, R10, R17, R18 | FP-RMCF0402-MFG | CMP-26527-000026-1 | 6 |  |  |  |  |  |  |
| 0_5%_0402 |  | R2, R3, R12, R13, R15 | RESC1005X40X25NL05T10 | CMP-2002-06457-1 | 5 |  |  |  |  |  |  |
| 100k | 100kΩ ±1% 0.063W 0402 Thick Film Chip Resistor AEC-Q200 compliant | R9, R11 | FP-RMCF0402-IPC_C | CMP-2000-06984-2 | 2 |  |  |  |  |  |  |
| 22_1%_1218 1.5W | RES Thick Film, 22.6Ω, 1%, 1.5W, 100ppm/°C, 1218 | R16 | FP-CRCW1218-HPe3-MFG | CMP-02407-011337-1 | 1 |  |  |  |  |  |  |
| ZED-F9T-00B | Multi-band GNSS Receiver with Nanosecond-level Timing Accuracy | U1 | GPS_ZED-F9T | GPS_ZED-F9T | 1 |  |  |  | ZED-F9T-00B |  |  |
| SN74LVC3G07DCUR | Triple Buffer/Driver With Open-Drain Output, DCU0008A, LARGE T&R | U3 | DCU0008A_N | CMP-0859-00615-3 | 1 |  |  |  |  |  |  |
| LPV511MGX/NOPB | micropower Rail-to-Rail Input and Output Operational Amplifier, 5-pin SC-70, Pb-Free | U4 | DCK0005A_N | CMP-0055-01065-3 | 1 |  |  |  |  |  |  |
